FILE_TYPE = MULTI_PHYS_TABLE;

PART 'XTAL_2'
CLASS=DISCRETE

{========================================================================================}
:CLS_PN             = JEDEC_TYPE          | ALT_SYMBOLS           | DESCRIPTION                                                                         | CPN_STATUS ;
{========================================================================================}
 'CL5000017A'       = 'SMC_Y2_161X059'    | '(SMC_Y2_161X059)'    | 'XTAL, 32.768KHZ, ¡À20PPM, 12.5PF, 65K¦¸, 0.1UW, 4.1*1.5*0.75MM, -40¡ÃC~+85¡ÃC, ROHS' |''
 'CL5001015A'       = 'SMC_Y2_126X059'    | '(SMC_Y2_126X059)'    | 'XTAL, 32.768KHZ, 20PPM, 12.5PF, 80KOHM, 3215'                                      |''
 'CL5001031A'       = 'SMC_Y2_315X177'    | '(SMC_Y2_315X177)'    | 'XTAL, 4.9152MHZ, 30PPM, 12PF, 8045'                                                |''
 'CL5003136A'       = 'SMC_Y2_315X177'    | '(SMC_Y2_315X177)'    | 'XTAL, 25MHZ, 8PF, 50PPM, -40C TO +150C'                                            |''
 'CL5003236A'       = 'SMC_Y2_315X177'    | '(SMC_Y2_315X177)'    | 'XTAL, 25MHZ, 8PF, 20PPM, -10C TO +70C, 8.0 X 4.5 X 1.8 MM, SMT'                    |''
 'G131-10010-01'    = 'SMC_Y2_126X059_V1' | '(SMC_Y2_126X059_V1)' | 'XTAL, 32.768KHZ,SMALL 3.2X1.5X0.8MM SIZE, CERAMIC'                                 |''
 'G131-10012-01'    = 'SMC_Y2_449X187'    | '(SMC_Y2_449X187)'    | 'XTAL,25.000MHZ,18PF,50PPM,2 PADS SMD,11.4X4.75X3.2'                                |'NFND'
 'G131-10028-01'    = 'SMC_Y2_126X059_V1' | '(SMC_Y2_126X059_V1)' | 'XTAL, 32.768KHZ, 12.5PF, +/-20PPM, 3.2MMX1.5MMX0.8MM'                              |'NFND'
 'G131-10037-01'    = 'SMC_Y2_449X185_V1' | '(SMC_Y2_449X185_V1)' | 'XTAL,12MHZ,18PF,30PPM,12.9MMX4.7MM,SMT'                                            |''
 'G131-10045-01'    = 'SMC_Y2_197X126_V2' | '(SMC_Y2_197X126_V2)' | 'XTAL,50.000000MHZ,19PF,15PPM,5.0X3.2X1.2MM,SMD'                                    |'NFND'
 'G131-10050-01'    = 'SMC_Y2_449X187_V1' | '(SMC_Y2_449X187_V1)' | 'XTAL,25.000MHZ,18PF,30PPM,SIZE 11.4 X4.75X3.2MM,2PIN,SMD'                          |'NFND'
 'G131-10034-01'    = 'SMC_Y2_461X197'    | '(SMC_Y2_461X197)'    | 'XTAL,25MHZ,10PF,20PPM,SMD'                                                         |''
 'G131-10058-01'    = 'SMC_Y2_126X059_V2' | '(SMC_Y2_126X059_V2)' | 'XTAL,32.768KHZ,12.5PF,20PPM,ESR 50KOHM,SMT'                                        |''
 'G131-10061-01'    = 'SMC_Y2_197X126_V2' | '(SMC_Y2_197X126_V2)' | 'XTAL,50.000000MHZ,85C,19PF,10PPM,5.0X3.2X1.2MM,SMD'                                |'NFND'
 'G131-10075-01'    = 'SMC_Y2_079X047'    | '(SMC_Y2_079X047)'    | 'XTAL,32.768KHZ,12.5PF,20PPM,2.0X1.2X0.6MM'                                         |''
 'G131-10024-01'    = 'SMC_Y2_197X126_V2' | '(SMC_Y2_197X126_V2)' | 'XTAL,50.000MHZ,15PPM,16PF,5MMX3.2MM,SMT'                                           |'NFND'
 'G131-10080-01'    = 'SMC_Y2_126X059_V3' | '(SMC_Y2_126X059_V3)' | 'XTAL,32.768KHZ,20PPM TOL,12.5PF,70KOHMESR,-0.04PPM/C STABILITY,3.3X1.6X0.9MM,SMT'  |''
 'A131-10028-IB'    = 'SMC_Y2_126X059_V1' | '(SMC_Y2_126X059_V1)' | 'XTAL,32.768KHZ,12.5PF,+/-20PPM,ESR_70KOHM,3.3X1.65X0.9MM'                          |''
 'G131-10028-02'    = 'SMC_Y2_126X059_V1' | '(SMC_Y2_126X059_V1)' | 'XTAL,32.768KHZ,12.5PF,+/-20PPM,ESR_70KOHM,3.3X1.65X0.9MM'                          |''

END_PART

END.

